# T6G (Grand Teton) — schematic netlist excerpt (pin names and nets, part order shuffled) for the footprints in the layout excerpt that follows; sources: Cadence DE-HDL packaged netlist, KiCad conversion of 04192023_DAF0TMB3IC0_F0TG_MB_C_brd_V02_OCP.brd

J109  CONN112_10137002101LF  CONN112_10137002-101LF IO  pkg HSD_F112D8_P2W1-2_RDH  page 119
  A1  = BMC_MONITER_BUF
  A2  = GND
  A3  = BIC_MONITER
  A4  = GND
  A5  = SMB_BMC_SWB_BUF_SCL
  A6  = GND
  A7  = SMB_BMC_SWB_BUF_SDA
  A8  = GND
  B1  = GND
  B2  = P5E_CPU1_P2_RX_BUF_DN<9>
  B3  = GND
  B4  = P5E_CPU1_P2_RX_BUF_DN<11>
  B5  = GND
  B6  = P5E_CPU1_P2_RX_BUF_DN<13>
  B7  = GND
  B8  = P5E_CPU1_P2_RX_BUF_DN<15>
  C1  = P5E_CPU1_P2_RX_BUF_DN<8>
  C2  = P5E_CPU1_P2_RX_BUF_DP<9>
  C3  = P5E_CPU1_P2_RX_BUF_DN<10>
  C4  = P5E_CPU1_P2_RX_BUF_DP<11>
  C5  = P5E_CPU1_P2_RX_BUF_DN<12>
  C6  = P5E_CPU1_P2_RX_BUF_DP<13>
  C7  = P5E_CPU1_P2_RX_BUF_DN<14>
  C8  = P5E_CPU1_P2_RX_BUF_DP<15>
  D1  = P5E_CPU1_P2_RX_BUF_DP<8>
  D2  = GND
  D3  = P5E_CPU1_P2_RX_BUF_DP<10>
  D4  = GND
  D5  = P5E_CPU1_P2_RX_BUF_DP<12>
  D6  = GND
  D7  = P5E_CPU1_P2_RX_BUF_DP<14>
  D8  = GND
  E1  = GND
  E2  = P5E_CPU1_P3_RX_BUF_DN<9>
  E3  = GND
  E4  = P5E_CPU1_P3_RX_BUF_DN<11>
  E5  = GND
  E6  = P5E_CPU1_P3_RX_BUF_DN<13>
  E7  = GND
  E8  = P5E_CPU1_P3_RX_BUF_DN<15>
  F1  = P5E_CPU1_P3_RX_BUF_DN<8>
  F2  = P5E_CPU1_P3_RX_BUF_DP<9>
  F3  = P5E_CPU1_P3_RX_BUF_DN<10>
  F4  = P5E_CPU1_P3_RX_BUF_DP<11>
  F5  = P5E_CPU1_P3_RX_BUF_DN<12>
  F6  = P5E_CPU1_P3_RX_BUF_DP<13>
  F7  = P5E_CPU1_P3_RX_BUF_DN<14>
  F8  = P5E_CPU1_P3_RX_BUF_DP<15>
  G1  = P5E_CPU1_P3_RX_BUF_DP<8>
  G2  = GND
  G3  = P5E_CPU1_P3_RX_BUF_DP<10>
  G4  = GND
  G5  = P5E_CPU1_P3_RX_BUF_DP<12>
  G6  = GND
  G7  = P5E_CPU1_P3_RX_BUF_DP<14>
  G8  = GND
  H1  = GND
  H2  = P5E_CPU1_P2_TX_BUF_C_DN<9>
  H3  = GND
  H4  = P5E_CPU1_P2_TX_BUF_C_DN<11>
  H5  = GND
  H6  = P5E_CPU1_P2_TX_BUF_C_DN<13>
  H7  = GND
  H8  = P5E_CPU1_P2_TX_BUF_C_DN<15>
  I1  = P5E_CPU1_P2_TX_BUF_C_DN<8>
  I2  = P5E_CPU1_P2_TX_BUF_C_DP<9>
  I3  = P5E_CPU1_P2_TX_BUF_C_DN<10>
  I4  = P5E_CPU1_P2_TX_BUF_C_DP<11>
  I5  = P5E_CPU1_P2_TX_BUF_C_DN<12>
  I6  = P5E_CPU1_P2_TX_BUF_C_DP<13>
  I7  = P5E_CPU1_P2_TX_BUF_C_DN<14>
  I8  = P5E_CPU1_P2_TX_BUF_C_DP<15>
  J1  = P5E_CPU1_P2_TX_BUF_C_DP<8>
  J2  = GND
  J3  = P5E_CPU1_P2_TX_BUF_C_DP<10>
  J4  = GND
  J5  = P5E_CPU1_P2_TX_BUF_C_DP<12>
  J6  = GND
  J7  = P5E_CPU1_P2_TX_BUF_C_DP<14>
  J8  = GND
  K1  = GND
  K2  = P5E_CPU1_P3_TX_BUF_C_DN<9>
  K3  = GND
  K4  = P5E_CPU1_P3_TX_BUF_C_DN<11>
  K5  = GND
  K6  = P5E_CPU1_P3_TX_BUF_C_DN<13>
  K7  = GND
  K8  = P5E_CPU1_P3_TX_BUF_C_DN<15>
  L1  = P5E_CPU1_P3_TX_BUF_C_DN<8>
  L2  = P5E_CPU1_P3_TX_BUF_C_DP<9>
  L3  = P5E_CPU1_P3_TX_BUF_C_DN<10>
  L4  = P5E_CPU1_P3_TX_BUF_C_DP<11>
  L5  = P5E_CPU1_P3_TX_BUF_C_DN<12>
  L6  = P5E_CPU1_P3_TX_BUF_C_DP<13>
  L7  = P5E_CPU1_P3_TX_BUF_C_DN<14>
  L8  = P5E_CPU1_P3_TX_BUF_C_DP<15>
  M1  = P5E_CPU1_P3_TX_BUF_C_DP<8>
  M2  = GND
  M3  = P5E_CPU1_P3_TX_BUF_C_DP<10>
  M4  = GND
  M5  = P5E_CPU1_P3_TX_BUF_C_DP<12>
  M6  = GND
  M7  = P5E_CPU1_P3_TX_BUF_C_DP<14>
  M8  = GND
  N1  = GND
  N2  = GPU_FPGA_EROT_FATALERR_N
  N3  = GND
  N4  = GPU_3V3IO_RSVD0_FFU
  N5  = GND
  N6  = GPU_3V3IO_RSVD1_FFU
  N7  = GND
  N8  = PRSNT_CABLE_GPU_B3_N

(kicad_pcb
	(version 20260206)
	(generator "pcbnew")
	(generator_version "10.0")
	(general
		(thickness 1.6)
		(legacy_teardrops no)
	)
	(paper "A4")
	(title_block
		(title "04192023_DAF0TMB3IC0_F0TG_MB_C_brd_V02_OCP.brd")
		(comment 1 "Grand Teton / footprint 1153 of 8354 (J109), pads 32-48 of 48")
	)
	(layers
		(0 "F.Cu" signal "TOP")
		(4 "In1.Cu" signal "GND")
		(6 "In2.Cu" signal "IN1")
		(8 "In3.Cu" signal "GND1")
		(10 "In4.Cu" signal "IN2")
		(12 "In5.Cu" signal "GND2")
		(14 "In6.Cu" signal "IN3")
		(16 "In7.Cu" signal "GND3")
		(18 "In8.Cu" signal "VCC")
		(20 "In9.Cu" signal "VCC1")
		(22 "In10.Cu" signal "GND4")
		(24 "In11.Cu" signal "IN4")
		(26 "In12.Cu" signal "GND5")
		(28 "In13.Cu" signal "IN5")
		(30 "In14.Cu" signal "GND6")
		(32 "In15.Cu" signal "IN6")
		(34 "In16.Cu" signal "GND7")
		(2 "B.Cu" signal "BOTTOM")
		(9 "F.Adhes" user "F.Adhesive")
		(11 "B.Adhes" user "B.Adhesive")
		(13 "F.Paste" user "Package Geometry/Pastemask Top")
		(15 "B.Paste" user "Package Geometry/Pastemask Bottom")
		(5 "F.SilkS" user "Ref Des/Silkscreen Top")
		(7 "B.SilkS" user "Ref Des/Silkscreen Bottom")
		(1 "F.Mask" user "Board Geometry/Soldermask Top")
		(3 "B.Mask" user "Board Geometry/Soldermask Bottom")
		(17 "Dwgs.User" user "User.Drawings")
		(19 "Cmts.User" user "User.Comments")
		(21 "Eco1.User" user "User.Eco1")
		(23 "Eco2.User" user "User.Eco2")
		(25 "Edge.Cuts" user "Board Geometry/Outline")
		(27 "Margin" user)
		(31 "F.CrtYd" user "Package Geometry/Place Bound Top")
		(29 "B.CrtYd" user "Package Geometry/Place Bound Bottom")
		(35 "F.Fab" user "Ref Des/Assembly Top")
		(33 "B.Fab" user "Ref Des/Assembly Bottom")
	)
	(footprint ""
		(layer "F.Cu")
		(at 142.750032 -440.489848)
		(property "Reference" "J109"
			(at 17.580102 23.22576 0)
			(unlocked yes)
			(layer "F.SilkS")
			(effects
				(font
					(size 0.7874 0.5842)
					(thickness 0.1524)
				)
				(justify left)
			)
		)
		(property "Value" ""
			(at 0 0 0)
			(layer "F.Fab")
			(effects
				(font
					(size 1.27 1.27)
				)
			)
		)
		(duplicate_pad_numbers_are_jumpers no)
		(pad "J8" thru_hole circle
			(at 13.999972 10.999978 180)
			(size 0.906272 0.906272)
			(drill 0.499872)
			(layers "*.Cu" "*.Mask")
			(remove_unused_layers no)
			(net "GND")
			(clearance 0.0508)
			(thermal_gap 0.0508)
		)
		(pad "K1" thru_hole circle
			(at 0 11.999976 180)
			(size 0.906272 0.906272)
			(drill 0.499872)
			(layers "*.Cu" "*.Mask")
			(remove_unused_layers no)
			(net "GND")
			(clearance 0.0508)
			(thermal_gap 0.0508)
		)
		(pad "K3" thru_hole circle
			(at 3.999992 11.999976 180)
			(size 0.906272 0.906272)
			(drill 0.499872)
			(layers "*.Cu" "*.Mask")
			(remove_unused_layers no)
			(net "GND")
			(clearance 0.0508)
			(thermal_gap 0.0508)
		)
		(pad "K5" thru_hole circle
			(at 7.999984 11.999976 180)
			(size 0.906272 0.906272)
			(drill 0.499872)
			(layers "*.Cu" "*.Mask")
			(remove_unused_layers no)
			(net "GND")
			(clearance 0.0508)
			(thermal_gap 0.0508)
		)
		(pad "K7" thru_hole circle
			(at 11.999976 11.999976 180)
			(size 0.906272 0.906272)
			(drill 0.499872)
			(layers "*.Cu" "*.Mask")
			(remove_unused_layers no)
			(net "GND")
			(clearance 0.0508)
			(thermal_gap 0.0508)
		)
		(pad "M2" thru_hole circle
			(at 1.999996 14.59992 180)
			(size 0.906272 0.906272)
			(drill 0.499872)
			(layers "*.Cu" "*.Mask")
			(remove_unused_layers no)
			(net "GND")
			(clearance 0.0508)
			(thermal_gap 0.0508)
		)
		(pad "M4" thru_hole circle
			(at 5.999988 14.59992 180)
			(size 0.906272 0.906272)
			(drill 0.499872)
			(layers "*.Cu" "*.Mask")
			(remove_unused_layers no)
			(net "GND")
			(clearance 0.0508)
			(thermal_gap 0.0508)
		)
		(pad "M6" thru_hole circle
			(at 9.99998 14.59992 180)
			(size 0.906272 0.906272)
			(drill 0.499872)
			(layers "*.Cu" "*.Mask")
			(remove_unused_layers no)
			(net "GND")
			(clearance 0.0508)
			(thermal_gap 0.0508)
		)
		(pad "M8" thru_hole circle
			(at 13.999972 14.59992 180)
			(size 0.906272 0.906272)
			(drill 0.499872)
			(layers "*.Cu" "*.Mask")
			(remove_unused_layers no)
			(net "GND")
			(clearance 0.0508)
			(thermal_gap 0.0508)
		)
		(pad "N1" thru_hole circle
			(at 0 15.599918 180)
			(size 0.906272 0.906272)
			(drill 0.499872)
			(layers "*.Cu" "*.Mask")
			(remove_unused_layers no)
			(net "GND")
			(clearance 0.0508)
			(thermal_gap 0.0508)
		)
		(pad "N2" thru_hole circle
			(at 1.999996 15.80007 180)
			(size 0.766318 0.766318)
			(drill 0.359918)
			(layers "*.Cu" "*.Mask")
			(remove_unused_layers no)
			(net "GPU_FPGA_EROT_FATALERR_N")
			(clearance 0.0508)
			(thermal_gap 0.0508)
		)
		(pad "N3" thru_hole circle
			(at 3.999992 15.599918 180)
			(size 0.906272 0.906272)
			(drill 0.499872)
			(layers "*.Cu" "*.Mask")
			(remove_unused_layers no)
			(net "GND")
			(clearance 0.0508)
			(thermal_gap 0.0508)
		)
		(pad "N4" thru_hole circle
			(at 5.999988 15.80007 180)
			(size 0.766318 0.766318)
			(drill 0.359918)
			(layers "*.Cu" "*.Mask")
			(remove_unused_layers no)
			(net "GPU_3V3IO_RSVD0_FFU")
			(clearance 0.0508)
			(thermal_gap 0.0508)
		)
		(pad "N5" thru_hole circle
			(at 7.999984 15.599918 180)
			(size 0.906272 0.906272)
			(drill 0.499872)
			(layers "*.Cu" "*.Mask")
			(remove_unused_layers no)
			(net "GND")
			(clearance 0.0508)
			(thermal_gap 0.0508)
		)
		(pad "N6" thru_hole circle
			(at 9.99998 15.80007 180)
			(size 0.766318 0.766318)
			(drill 0.359918)
			(layers "*.Cu" "*.Mask")
			(remove_unused_layers no)
			(net "GPU_3V3IO_RSVD1_FFU")
			(clearance 0.0508)
			(thermal_gap 0.0508)
		)
		(pad "N7" thru_hole circle
			(at 11.999976 15.599918 180)
			(size 0.906272 0.906272)
			(drill 0.499872)
			(layers "*.Cu" "*.Mask")
			(remove_unused_layers no)
			(net "GND")
			(clearance 0.0508)
			(thermal_gap 0.0508)
		)
		(pad "N8" thru_hole circle
			(at 13.999972 15.80007 180)
			(size 0.766318 0.766318)
			(drill 0.359918)
			(layers "*.Cu" "*.Mask")
			(remove_unused_layers no)
			(net "PRSNT_CABLE_GPU_B3_N")
			(clearance 0.0508)
			(thermal_gap 0.0508)
		)
	)
)
